# TIMECARD (Time Appliance Project (Time Card)) — schematic netlist excerpt (pin names and nets, part order shuffled) for the footprints in the layout excerpt that follows; sources: Cadence DE-HDL packaged netlist, KiCad conversion of R4006-B0001-02_R01.brd

R116  RESISTOR  33OHM 1%  pkg SMC_0402R_H016  page 22 : \1\ = GPS_RST_N ; \2\ = FPGA_OUT_GPS_RST_N

(kicad_pcb
	(version 20260206)
	(generator "pcbnew")
	(generator_version "10.0")
	(general
		(thickness 1.6)
		(legacy_teardrops no)
	)
	(paper "A4")
	(title_block
		(title "timecard-production-celestica-r4006 — R4006-B0001-02_R01.brd")
		(comment 1 "Time Appliance Project (Time Card) / footprints 435-435 of 1113")
	)
	(layers
		(0 "F.Cu" signal "TOP")
		(4 "In1.Cu" signal "L02_GND1")
		(6 "In2.Cu" signal "L03_SIG1")
		(8 "In3.Cu" signal "L04_GND2")
		(10 "In4.Cu" signal "L05_VCC1")
		(12 "In5.Cu" signal "L06_VCC2")
		(14 "In6.Cu" signal "L07_GND3")
		(16 "In7.Cu" signal "L08_SIG2")
		(18 "In8.Cu" signal "L09_GND4")
		(2 "B.Cu" signal "BOTTOM")
		(9 "F.Adhes" user "F.Adhesive")
		(11 "B.Adhes" user "B.Adhesive")
		(13 "F.Paste" user "Package Geometry/Pastemask Top")
		(15 "B.Paste" user "Package Geometry/Pastemask Bottom")
		(5 "F.SilkS" user "Ref Des/Silkscreen Top")
		(7 "B.SilkS" user "Ref Des/Silkscreen Bottom")
		(1 "F.Mask" user "Board Geometry/Soldermask Top")
		(3 "B.Mask" user "Board Geometry/Soldermask Bottom")
		(17 "Dwgs.User" user "User.Drawings")
		(19 "Cmts.User" user "User.Comments")
		(21 "Eco1.User" user "User.Eco1")
		(23 "Eco2.User" user "User.Eco2")
		(25 "Edge.Cuts" user "Board Geometry/Outline")
		(27 "Margin" user)
		(31 "F.CrtYd" user "Package Geometry/Place Bound Top")
		(29 "B.CrtYd" user "Package Geometry/Place Bound Bottom")
		(35 "F.Fab" user "Ref Des/Assembly Top")
		(33 "B.Fab" user "Ref Des/Assembly Bottom")
	)
	(footprint ""
		(layer "F.Cu")
		(at 121.539 -89.535 -90)
		(property "Reference" "R116"
			(at 3.429 0.21463 90)
			(unlocked yes)
			(layer "F.SilkS")
			(effects
				(font
					(size 0.7874 0.5842)
					(thickness 0.1524)
				)
			)
		)
		(property "Value" "VAL*"
			(at 0.02032 2.13233 270)
			(unlocked yes)
			(layer "F.Fab")
			(hide yes)
			(effects
				(font
					(size 0.7874 0.5842)
					(thickness 0.1524)
				)
			)
		)
		(property "Device Type" "RESISTOR-G155-133R0-01,33OHM,1%"
			(at 0.008382 1.210564 270)
			(unlocked yes)
			(layer "F.Fab")
			(hide yes)
			(effects
				(font
					(size 0.7874 0.5842)
					(thickness 0.1524)
				)
			)
		)
		(property "User Part Number" "PARTNUM*"
			(at 0.02032 4.024884 270)
			(unlocked yes)
			(layer "Cmts.User")
			(hide yes)
			(effects
				(font
					(size 0.7874 0.5842)
					(thickness 0.1524)
				)
			)
		)
		(property "Tolerance" "TOL*"
			(at 0.044704 3.05435 270)
			(unlocked yes)
			(layer "Cmts.User")
			(hide yes)
			(effects
				(font
					(size 0.7874 0.5842)
					(thickness 0.1524)
				)
			)
		)
		(duplicate_pad_numbers_are_jumpers no)
		(fp_line
			(start -1.143 0.5588)
			(end 1.143 0.5588)
			(stroke
				(width 0.1)
				(type default)
			)
			(layer "F.SilkS")
		)
		(fp_line
			(start 1.143 0.5588)
			(end 1.143 -0.5588)
			(stroke
				(width 0.1)
				(type default)
			)
			(layer "F.SilkS")
		)
		(fp_line
			(start -1.143 -0.5588)
			(end -1.143 0.5588)
			(stroke
				(width 0.1)
				(type default)
			)
			(layer "F.SilkS")
		)
		(fp_line
			(start 1.143 -0.5588)
			(end -1.143 -0.5588)
			(stroke
				(width 0.1)
				(type default)
			)
			(layer "F.SilkS")
		)
		(fp_rect
			(start 1.143 -0.5588)
			(end -1.143 0.5588)
			(stroke
				(width 0)
				(type default)
			)
			(fill no)
			(layer "F.CrtYd")
		)
		(fp_line
			(start -0.508 0.3048)
			(end 0.508 0.3048)
			(stroke
				(width 0.1)
				(type default)
			)
			(layer "F.Fab")
		)
		(fp_line
			(start 0.508 0.3048)
			(end 0.508 -0.3048)
			(stroke
				(width 0.1)
				(type default)
			)
			(layer "F.Fab")
		)
		(fp_line
			(start -0.508 -0.3048)
			(end -0.508 0.3048)
			(stroke
				(width 0.1)
				(type default)
			)
			(layer "F.Fab")
		)
		(fp_line
			(start 0.508 -0.3048)
			(end -0.508 -0.3048)
			(stroke
				(width 0.1)
				(type default)
			)
			(layer "F.Fab")
		)
		(pad "1" smd rect
			(at -0.5334 0 270)
			(size 0.7112 0.6096)
			(layers "F.Cu" "F.Mask" "F.Paste")
			(net "GPS_RST_N")
		)
		(pad "2" smd rect
			(at 0.5334 0 270)
			(size 0.7112 0.6096)
			(layers "F.Cu" "F.Mask" "F.Paste")
			(net "FPGA_OUT_GPS_RST_N")
		)
		(zone
			(layer "F.Cu")
			(hatch none 0.5)
			(connect_pads
				(clearance 0)
			)
			(min_thickness 0.25)
			(keepout
				(tracks allowed)
				(vias not_allowed)
				(pads allowed)
				(copperpour not_allowed)
				(footprints allowed)
			)
			(placement
				(enabled no)
				(sheetname "")
			)
			(fill
				(thermal_gap 0.5)
				(thermal_bridge_width 0.5)
				(island_removal_mode 0)
			)
			(polygon
				(pts
					(xy 121.8438 -89.4588) (xy 121.8438 -89.6112) (xy 121.2342 -89.6112) (xy 121.2342 -89.4588)
				)
			)
		)
	)
)
